(kicad_pcb
	(version 20260206)
	(generator "pcbnew")
	(generator_version "10.0")
	(general
		(thickness 1.6)
		(legacy_teardrops no)
	)
	(paper "A4")
	(title_block
		(title "panther-plus-userver — 13130-1b_20150205.brd")
		(comment 1 "Honey Badger (Wiwynn) / footprints 737-743 of 1509")
	)
	(layers
		(0 "F.Cu" signal "TOP")
		(4 "In1.Cu" signal "L2")
		(6 "In2.Cu" signal "L3")
		(8 "In3.Cu" signal "L4")
		(10 "In4.Cu" signal "L5")
		(12 "In5.Cu" signal "L6")
		(14 "In6.Cu" signal "L7")
		(16 "In7.Cu" signal "L8")
		(18 "In8.Cu" signal "L9")
		(20 "In9.Cu" signal "L10")
		(22 "In10.Cu" signal "L11")
		(2 "B.Cu" signal "BOTTOM")
		(9 "F.Adhes" user "F.Adhesive")
		(11 "B.Adhes" user "B.Adhesive")
		(13 "F.Paste" user "Package Geometry/Pastemask Top")
		(15 "B.Paste" user "Package Geometry/Pastemask Bottom")
		(5 "F.SilkS" user "Ref Des/Silkscreen Top")
		(7 "B.SilkS" user "Ref Des/Silkscreen Bottom")
		(1 "F.Mask" user "Board Geometry/Soldermask Top")
		(3 "B.Mask" user "Board Geometry/Soldermask Bottom")
		(17 "Dwgs.User" user "User.Drawings")
		(19 "Cmts.User" user "User.Comments")
		(21 "Eco1.User" user "User.Eco1")
		(23 "Eco2.User" user "User.Eco2")
		(25 "Edge.Cuts" user "Board Geometry/Outline")
		(27 "Margin" user)
		(31 "F.CrtYd" user "Package Geometry/Place Bound Top")
		(29 "B.CrtYd" user "Package Geometry/Place Bound Bottom")
		(35 "F.Fab" user "Ref Des/Assembly Top")
		(33 "B.Fab" user "Ref Des/Assembly Bottom")
	)
	(footprint ""
		(layer "F.Cu")
		(at 12.573 -55.245 -90)
		(property "Reference" "PC48"
			(at 0 0 270)
			(layer "F.SilkS")
			(hide yes)
			(effects
				(font
					(size 1.27 1.27)
				)
			)
		)
		(property "Value" "SCD22U10V2KX-1GP"
			(at 1.8923 -1.2065 270)
			(unlocked yes)
			(layer "F.Fab")
			(hide yes)
			(effects
				(font
					(size 1.016 1.016)
					(thickness 0.1524)
				)
			)
		)
		(property "Device Type" "C402H22"
			(at 1.8923 -2.7305 270)
			(unlocked yes)
			(layer "F.Fab")
			(hide yes)
			(effects
				(font
					(size 1.016 1.016)
					(thickness 0.1524)
				)
			)
		)
		(duplicate_pad_numbers_are_jumpers no)
		(fp_rect
			(start -0.381 0.7366)
			(end 0.381 -0.7366)
			(stroke
				(width 0)
				(type default)
			)
			(fill no)
			(layer "F.CrtYd")
		)
		(fp_rect
			(start -0.381 0.7366)
			(end 0.381 -0.7366)
			(stroke
				(width 0)
				(type default)
			)
			(fill no)
			(layer "F.Fab")
		)
		(pad "1" smd custom
			(at 0 -0.4572 270)
			(size 0.1143 0.1143)
			(layers "F.Cu" "F.Mask" "F.Paste")
			(net "VR_PVCCP_IMON")
			(options
				(clearance outline)
				(anchor circle)
			)
			(primitives
				(gr_poly
					(pts
						(arc
							(start -0.254 -0.1778)
							(mid -0.239121 -0.213721)
							(end -0.2032 -0.2286)
						)
						(arc
							(start 0.2032 -0.2286)
							(mid 0.239121 -0.213721)
							(end 0.254 -0.1778)
						)
						(arc
							(start 0.254 0.1778)
							(mid 0.239121 0.213721)
							(end 0.2032 0.2286)
						)
						(arc
							(start -0.2032 0.2286)
							(mid -0.239121 0.213721)
							(end -0.254 0.1778)
						)
					)
					(width 0)
					(fill yes)
				)
			)
		)
		(pad "2" smd custom
			(at 0 0.4572 270)
			(size 0.1143 0.1143)
			(layers "F.Cu" "F.Mask" "F.Paste")
			(net "GND")
			(options
				(clearance outline)
				(anchor circle)
			)
			(primitives
				(gr_poly
					(pts
						(arc
							(start -0.254 -0.1778)
							(mid -0.239121 -0.213721)
							(end -0.2032 -0.2286)
						)
						(arc
							(start 0.2032 -0.2286)
							(mid 0.239121 -0.213721)
							(end 0.254 -0.1778)
						)
						(arc
							(start 0.254 0.1778)
							(mid 0.239121 0.213721)
							(end 0.2032 0.2286)
						)
						(arc
							(start -0.2032 0.2286)
							(mid -0.239121 0.213721)
							(end -0.254 0.1778)
						)
					)
					(width 0)
					(fill yes)
				)
			)
		)
	)
	(footprint ""
		(layer "F.Cu")
		(at 69.9262 -43.6626)
		(property "Reference" "R71"
			(at 0 0 0)
			(layer "F.SilkS")
			(hide yes)
			(effects
				(font
					(size 1.27 1.27)
				)
			)
		)
		(property "Value" "4K7R2F-GP"
			(at 0.064008 -3.993896 0)
			(unlocked yes)
			(layer "F.Fab")
			(hide yes)
			(effects
				(font
					(size 1.016 1.016)
					(thickness 0.1524)
				)
			)
		)
		(property "Device Type" "R402H16"
			(at 0.064008 -5.517896 0)
			(unlocked yes)
			(layer "F.Fab")
			(hide yes)
			(effects
				(font
					(size 1.016 1.016)
					(thickness 0.1524)
				)
			)
		)
		(duplicate_pad_numbers_are_jumpers no)
		(fp_rect
			(start -0.381 0.8382)
			(end 0.381 -0.8382)
			(stroke
				(width 0)
				(type default)
			)
			(fill no)
			(layer "F.CrtYd")
		)
		(fp_rect
			(start -0.381 0.8382)
			(end 0.381 -0.8382)
			(stroke
				(width 0)
				(type default)
			)
			(fill no)
			(layer "F.Fab")
		)
		(pad "1" smd custom
			(at 0 -0.4318)
			(size 0.127 0.127)
			(layers "F.Cu" "F.Mask" "F.Paste")
			(net "P3V3")
			(options
				(clearance outline)
				(anchor circle)
			)
			(primitives
				(gr_poly
					(pts
						(arc
							(start -0.2032 -0.2794)
							(mid -0.239121 -0.264521)
							(end -0.254 -0.2286)
						)
						(arc
							(start -0.254 0.2286)
							(mid -0.239121 0.264521)
							(end -0.2032 0.2794)
						)
						(arc
							(start 0.2032 0.2794)
							(mid 0.239121 0.264521)
							(end 0.254 0.2286)
						)
						(arc
							(start 0.254 -0.2286)
							(mid 0.239121 -0.264521)
							(end 0.2032 -0.2794)
						)
					)
					(width 0)
					(fill yes)
				)
			)
		)
		(pad "2" smd custom
			(at 0 0.4318)
			(size 0.127 0.127)
			(layers "F.Cu" "F.Mask" "F.Paste")
			(net "SMBUS_PECI_DATA")
			(options
				(clearance outline)
				(anchor circle)
			)
			(primitives
				(gr_poly
					(pts
						(arc
							(start -0.2032 -0.2794)
							(mid -0.239121 -0.264521)
							(end -0.254 -0.2286)
						)
						(arc
							(start -0.254 0.2286)
							(mid -0.239121 0.264521)
							(end -0.2032 0.2794)
						)
						(arc
							(start 0.2032 0.2794)
							(mid 0.239121 0.264521)
							(end 0.254 0.2286)
						)
						(arc
							(start 0.254 -0.2286)
							(mid 0.239121 -0.264521)
							(end 0.2032 -0.2794)
						)
					)
					(width 0)
					(fill yes)
				)
			)
		)
	)
	(footprint ""
		(layer "F.Cu")
		(at 162.5092 -48.5648)
		(property "Reference" "R207"
			(at 0 0 0)
			(layer "F.SilkS")
			(hide yes)
			(effects
				(font
					(size 1.27 1.27)
				)
			)
		)
		(property "Value" "0R2J-2-GP"
			(at 1.7907 -1.1176 0)
			(unlocked yes)
			(layer "F.Fab")
			(hide yes)
			(effects
				(font
					(size 1.016 1.016)
					(thickness 0.1524)
				)
			)
		)
		(property "Device Type" "R402H16"
			(at 1.7907 -2.6416 0)
			(unlocked yes)
			(layer "F.Fab")
			(hide yes)
			(effects
				(font
					(size 1.016 1.016)
					(thickness 0.1524)
				)
			)
		)
		(duplicate_pad_numbers_are_jumpers no)
		(fp_rect
			(start -0.381 0.8382)
			(end 0.381 -0.8382)
			(stroke
				(width 0)
				(type default)
			)
			(fill no)
			(layer "F.CrtYd")
		)
		(fp_rect
			(start -0.381 0.8382)
			(end 0.381 -0.8382)
			(stroke
				(width 0)
				(type default)
			)
			(fill no)
			(layer "F.Fab")
		)
		(pad "1" smd custom
			(at 0 -0.4318)
			(size 0.127 0.127)
			(layers "F.Cu" "F.Mask" "F.Paste")
			(net "XDP_SOC_CPU_TMS")
			(options
				(clearance outline)
				(anchor circle)
			)
			(primitives
				(gr_poly
					(pts
						(arc
							(start -0.2032 -0.2794)
							(mid -0.239121 -0.264521)
							(end -0.254 -0.2286)
						)
						(arc
							(start -0.254 0.2286)
							(mid -0.239121 0.264521)
							(end -0.2032 0.2794)
						)
						(arc
							(start 0.2032 0.2794)
							(mid 0.239121 0.264521)
							(end 0.254 0.2286)
						)
						(arc
							(start 0.254 -0.2286)
							(mid 0.239121 -0.264521)
							(end 0.2032 -0.2794)
						)
					)
					(width 0)
					(fill yes)
				)
			)
		)
		(pad "2" smd custom
			(at 0 0.4318)
			(size 0.127 0.127)
			(layers "F.Cu" "F.Mask" "F.Paste")
			(net "XDP_SOC_CPU_TMS_S")
			(options
				(clearance outline)
				(anchor circle)
			)
			(primitives
				(gr_poly
					(pts
						(arc
							(start -0.2032 -0.2794)
							(mid -0.239121 -0.264521)
							(end -0.254 -0.2286)
						)
						(arc
							(start -0.254 0.2286)
							(mid -0.239121 0.264521)
							(end -0.2032 0.2794)
						)
						(arc
							(start 0.2032 0.2794)
							(mid 0.239121 0.264521)
							(end 0.254 0.2286)
						)
						(arc
							(start 0.254 -0.2286)
							(mid 0.239121 -0.264521)
							(end 0.2032 -0.2794)
						)
					)
					(width 0)
					(fill yes)
				)
			)
		)
	)
	(footprint ""
		(layer "F.Cu")
		(at 205.105 -21.463 180)
		(property "Reference" "R224"
			(at 0 0 180)
			(layer "F.SilkS")
			(hide yes)
			(effects
				(font
					(size 1.27 1.27)
				)
			)
		)
		(property "Value" "10KR2F-2-GP"
			(at 1.7907 -1.1176 180)
			(unlocked yes)
			(layer "F.Fab")
			(hide yes)
			(effects
				(font
					(size 1.016 1.016)
					(thickness 0.1524)
				)
			)
		)
		(property "Device Type" "R402H16"
			(at 1.7907 -2.6416 180)
			(unlocked yes)
			(layer "F.Fab")
			(hide yes)
			(effects
				(font
					(size 1.016 1.016)
					(thickness 0.1524)
				)
			)
		)
		(duplicate_pad_numbers_are_jumpers no)
		(fp_rect
			(start -0.381 0.8382)
			(end 0.381 -0.8382)
			(stroke
				(width 0)
				(type default)
			)
			(fill no)
			(layer "F.CrtYd")
		)
		(fp_rect
			(start -0.381 0.8382)
			(end 0.381 -0.8382)
			(stroke
				(width 0)
				(type default)
			)
			(fill no)
			(layer "F.Fab")
		)
		(pad "1" smd custom
			(at 0 -0.4318 180)
			(size 0.127 0.127)
			(layers "F.Cu" "F.Mask" "F.Paste")
			(net "P3V3_STBY")
			(options
				(clearance outline)
				(anchor circle)
			)
			(primitives
				(gr_poly
					(pts
						(arc
							(start -0.2032 -0.2794)
							(mid -0.239121 -0.264521)
							(end -0.254 -0.2286)
						)
						(arc
							(start -0.254 0.2286)
							(mid -0.239121 0.264521)
							(end -0.2032 0.2794)
						)
						(arc
							(start 0.2032 0.2794)
							(mid 0.239121 0.264521)
							(end 0.254 0.2286)
						)
						(arc
							(start 0.254 -0.2286)
							(mid 0.239121 -0.264521)
							(end 0.2032 -0.2794)
						)
					)
					(width 0)
					(fill yes)
				)
			)
		)
		(pad "2" smd custom
			(at 0 0.4318 180)
			(size 0.127 0.127)
			(layers "F.Cu" "F.Mask" "F.Paste")
			(net "JTAG_CPU_PLD_TDO")
			(options
				(clearance outline)
				(anchor circle)
			)
			(primitives
				(gr_poly
					(pts
						(arc
							(start -0.2032 -0.2794)
							(mid -0.239121 -0.264521)
							(end -0.254 -0.2286)
						)
						(arc
							(start -0.254 0.2286)
							(mid -0.239121 0.264521)
							(end -0.2032 0.2794)
						)
						(arc
							(start 0.2032 0.2794)
							(mid 0.239121 0.264521)
							(end 0.254 0.2286)
						)
						(arc
							(start 0.254 -0.2286)
							(mid 0.239121 -0.264521)
							(end 0.2032 -0.2794)
						)
					)
					(width 0)
					(fill yes)
				)
			)
		)
	)
	(footprint ""
		(layer "F.Cu")
		(at 60.198 -21.844 -90)
		(property "Reference" "Q10"
			(at 0 0 270)
			(layer "F.SilkS")
			(hide yes)
			(effects
				(font
					(size 1.27 1.27)
				)
			)
		)
		(property "Value" "2N7002A-7-GP"
			(at 0.127 -8.9662 270)
			(unlocked yes)
			(layer "F.Fab")
			(hide yes)
			(effects
				(font
					(size 1.016 1.016)
					(thickness 0.1524)
				)
			)
		)
		(property "Device Type" "SOT23DGS2D4H48"
			(at 0.127 -10.4902 270)
			(unlocked yes)
			(layer "F.Fab")
			(hide yes)
			(effects
				(font
					(size 1.016 1.016)
					(thickness 0.1524)
				)
			)
		)
		(duplicate_pad_numbers_are_jumpers no)
		(fp_line
			(start -1.7145 0.4445)
			(end 1.7145 0.4445)
			(stroke
				(width 0.1524)
				(type default)
			)
			(layer "F.SilkS")
		)
		(fp_line
			(start 1.7145 0.4445)
			(end 1.7145 -0.4445)
			(stroke
				(width 0.1524)
				(type default)
			)
			(layer "F.SilkS")
		)
		(fp_line
			(start -1.7145 -0.4445)
			(end -1.7145 0.4445)
			(stroke
				(width 0.1524)
				(type default)
			)
			(layer "F.SilkS")
		)
		(fp_line
			(start 1.7145 -0.4445)
			(end -1.7145 -0.4445)
			(stroke
				(width 0.1524)
				(type default)
			)
			(layer "F.SilkS")
		)
		(fp_poly
			(pts
				(xy -1.4224 1.5621) (xy -1.4224 0.9017) (xy -1.7145 0.9017) (xy -1.7145 -0.9017) (xy -0.4699 -0.9017)
				(xy -0.4699 -1.5621) (xy 0.4699 -1.5621) (xy 0.4699 -0.9017) (xy 1.7145 -0.9017) (xy 1.7145 0.9017)
				(xy 1.4224 0.9017) (xy 1.4224 1.5621) (xy 0.4826 1.5621) (xy 0.4826 0.9017) (xy -0.4826 0.9017)
				(xy -0.4826 1.5621)
			)
			(stroke
				(width 0)
				(type default)
			)
			(fill no)
			(layer "F.CrtYd")
		)
		(fp_poly
			(pts
				(xy -1.4224 1.5621) (xy -1.4224 0.9017) (xy -1.7145 0.9017) (xy -1.7145 -0.9017) (xy -0.4699 -0.9017)
				(xy -0.4699 -1.5621) (xy 0.4699 -1.5621) (xy 0.4699 -0.9017) (xy 1.7145 -0.9017) (xy 1.7145 0.9017)
				(xy 1.4224 0.9017) (xy 1.4224 1.5621) (xy 0.4826 1.5621) (xy 0.4826 0.9017) (xy -0.4826 0.9017)
				(xy -0.4826 1.5621)
			)
			(stroke
				(width 0)
				(type default)
			)
			(fill no)
			(layer "F.Fab")
		)
		(pad "D" smd custom
			(at 0 -1.069086 270)
			(size 0.17145 0.17145)
			(layers "F.Cu" "F.Mask" "F.Paste")
			(net "PWRGD_P1V8_PG")
			(options
				(clearance outline)
				(anchor circle)
			)
			(primitives
				(gr_poly
					(pts
						(arc
							(start -0.1397 0.3683)
							(mid -0.283384 0.308784)
							(end -0.3429 0.1651)
						)
						(arc
							(start -0.3429 -0.1651)
							(mid -0.283384 -0.308784)
							(end -0.1397 -0.3683)
						)
						(arc
							(start 0.1397 -0.3683)
							(mid 0.283384 -0.308784)
							(end 0.3429 -0.1651)
						)
						(arc
							(start 0.3429 0.1651)
							(mid 0.283384 0.308784)
							(end 0.1397 0.3683)
						)
					)
					(width 0)
					(fill yes)
				)
			)
		)
		(pad "G" smd custom
			(at -0.94996 1.069086 270)
			(size 0.17145 0.17145)
			(layers "F.Cu" "F.Mask" "F.Paste")
			(net "P1V8_G")
			(options
				(clearance outline)
				(anchor circle)
			)
			(primitives
				(gr_poly
					(pts
						(arc
							(start -0.1397 0.3683)
							(mid -0.283384 0.308784)
							(end -0.3429 0.1651)
						)
						(arc
							(start -0.3429 -0.1651)
							(mid -0.283384 -0.308784)
							(end -0.1397 -0.3683)
						)
						(arc
							(start 0.1397 -0.3683)
							(mid 0.283384 -0.308784)
							(end 0.3429 -0.1651)
						)
						(arc
							(start 0.3429 0.1651)
							(mid 0.283384 0.308784)
							(end 0.1397 0.3683)
						)
					)
					(width 0)
					(fill yes)
				)
			)
		)
		(pad "S" smd custom
			(at 0.94996 1.069086 270)
			(size 0.17145 0.17145)
			(layers "F.Cu" "F.Mask" "F.Paste")
			(net "GND")
			(options
				(clearance outline)
				(anchor circle)
			)
			(primitives
				(gr_poly
					(pts
						(arc
							(start -0.1397 0.3683)
							(mid -0.283384 0.308784)
							(end -0.3429 0.1651)
						)
						(arc
							(start -0.3429 -0.1651)
							(mid -0.283384 -0.308784)
							(end -0.1397 -0.3683)
						)
						(arc
							(start 0.1397 -0.3683)
							(mid 0.283384 -0.308784)
							(end 0.3429 -0.1651)
						)
						(arc
							(start 0.3429 0.1651)
							(mid 0.283384 0.308784)
							(end 0.1397 0.3683)
						)
					)
					(width 0)
					(fill yes)
				)
			)
		)
	)
	(footprint ""
		(layer "F.Cu")
		(at 6.9088 -32.004 180)
		(property "Reference" "PR202"
			(at 0 0 180)
			(layer "F.SilkS")
			(hide yes)
			(effects
				(font
					(size 1.27 1.27)
				)
			)
		)
		(property "Value" "73K2R2F-GP"
			(at 1.7907 -1.1176 180)
			(unlocked yes)
			(layer "F.Fab")
			(hide yes)
			(effects
				(font
					(size 1.016 1.016)
					(thickness 0.1524)
				)
			)
		)
		(property "Device Type" "R402H16"
			(at 1.7907 -2.6416 180)
			(unlocked yes)
			(layer "F.Fab")
			(hide yes)
			(effects
				(font
					(size 1.016 1.016)
					(thickness 0.1524)
				)
			)
		)
		(duplicate_pad_numbers_are_jumpers no)
		(fp_rect
			(start -0.381 0.8382)
			(end 0.381 -0.8382)
			(stroke
				(width 0)
				(type default)
			)
			(fill no)
			(layer "F.CrtYd")
		)
		(fp_rect
			(start -0.381 0.8382)
			(end 0.381 -0.8382)
			(stroke
				(width 0)
				(type default)
			)
			(fill no)
			(layer "F.Fab")
		)
		(pad "1" smd custom
			(at 0 -0.4318 180)
			(size 0.127 0.127)
			(layers "F.Cu" "F.Mask" "F.Paste")
			(net "AGND_P3V3_STBY")
			(options
				(clearance outline)
				(anchor circle)
			)
			(primitives
				(gr_poly
					(pts
						(arc
							(start -0.2032 -0.2794)
							(mid -0.239121 -0.264521)
							(end -0.254 -0.2286)
						)
						(arc
							(start -0.254 0.2286)
							(mid -0.239121 0.264521)
							(end -0.2032 0.2794)
						)
						(arc
							(start 0.2032 0.2794)
							(mid 0.239121 0.264521)
							(end 0.254 0.2286)
						)
						(arc
							(start 0.254 -0.2286)
							(mid 0.239121 -0.264521)
							(end 0.2032 -0.2794)
						)
					)
					(width 0)
					(fill yes)
				)
			)
		)
		(pad "2" smd custom
			(at 0 0.4318 180)
			(size 0.127 0.127)
			(layers "F.Cu" "F.Mask" "F.Paste")
			(net "P3V3_STBY_TRIP")
			(options
				(clearance outline)
				(anchor circle)
			)
			(primitives
				(gr_poly
					(pts
						(arc
							(start -0.2032 -0.2794)
							(mid -0.239121 -0.264521)
							(end -0.254 -0.2286)
						)
						(arc
							(start -0.254 0.2286)
							(mid -0.239121 0.264521)
							(end -0.2032 0.2794)
						)
						(arc
							(start 0.2032 0.2794)
							(mid 0.239121 0.264521)
							(end 0.254 0.2286)
						)
						(arc
							(start 0.254 -0.2286)
							(mid 0.239121 -0.264521)
							(end 0.2032 -0.2794)
						)
					)
					(width 0)
					(fill yes)
				)
			)
		)
	)
	(footprint ""
		(layer "F.Cu")
		(at 187.198 -50.673)
		(property "Reference" "R209"
			(at 0 0 0)
			(layer "F.SilkS")
			(hide yes)
			(effects
				(font
					(size 1.27 1.27)
				)
			)
		)
		(property "Value" "12K1R2F-L1-GP"
			(at 0.064008 -3.993896 0)
			(unlocked yes)
			(layer "F.Fab")
			(hide yes)
			(effects
				(font
					(size 1.016 1.016)
					(thickness 0.1524)
				)
			)
		)
		(property "Device Type" "R402H16"
			(at 0.064008 -5.517896 0)
			(unlocked yes)
			(layer "F.Fab")
			(hide yes)
			(effects
				(font
					(size 1.016 1.016)
					(thickness 0.1524)
				)
			)
		)
		(duplicate_pad_numbers_are_jumpers no)
		(fp_rect
			(start -0.381 0.8382)
			(end 0.381 -0.8382)
			(stroke
				(width 0)
				(type default)
			)
			(fill no)
			(layer "F.CrtYd")
		)
		(fp_rect
			(start -0.381 0.8382)
			(end 0.381 -0.8382)
			(stroke
				(width 0)
				(type default)
			)
			(fill no)
			(layer "F.Fab")
		)
		(pad "1" smd custom
			(at 0 -0.4318)
			(size 0.127 0.127)
			(layers "F.Cu" "F.Mask" "F.Paste")
			(net "PV_VDDR")
			(options
				(clearance outline)
				(anchor circle)
			)
			(primitives
				(gr_poly
					(pts
						(arc
							(start -0.2032 -0.2794)
							(mid -0.239121 -0.264521)
							(end -0.254 -0.2286)
						)
						(arc
							(start -0.254 0.2286)
							(mid -0.239121 0.264521)
							(end -0.2032 0.2794)
						)
						(arc
							(start 0.2032 0.2794)
							(mid 0.239121 0.264521)
							(end 0.254 0.2286)
						)
						(arc
							(start 0.254 -0.2286)
							(mid 0.239121 -0.264521)
							(end 0.2032 -0.2794)
						)
					)
					(width 0)
					(fill yes)
				)
			)
		)
		(pad "2" smd custom
			(at 0 0.4318)
			(size 0.127 0.127)
			(layers "F.Cu" "F.Mask" "F.Paste")
			(net "PV_VDDR_VREF_RW")
			(options
				(clearance outline)
				(anchor circle)
			)
			(primitives
				(gr_poly
					(pts
						(arc
							(start -0.2032 -0.2794)
							(mid -0.239121 -0.264521)
							(end -0.254 -0.2286)
						)
						(arc
							(start -0.254 0.2286)
							(mid -0.239121 0.264521)
							(end -0.2032 0.2794)
						)
						(arc
							(start 0.2032 0.2794)
							(mid 0.239121 0.264521)
							(end 0.254 0.2286)
						)
						(arc
							(start 0.254 -0.2286)
							(mid 0.239121 -0.264521)
							(end 0.2032 -0.2794)
						)
					)
					(width 0)
					(fill yes)
				)
			)
		)
	)
)
